%FSTAX25Y25*%
%MOIN*%
%SFA1B1*%

%IPPOS*%
%ADD63R,0.314960X0.135830*%
%ADD64R,1.354330X0.230320*%
%ADD83R,0.036000X0.173000*%
%ADD84R,0.036000X0.134000*%
%ADD100C,0.073980*%
%ADD101C,0.083000*%
%ADD102R,0.067060X0.067060*%
%ADD103C,0.067060*%
%ADD104C,0.008000*%
%ADD105C,0.029660*%
%ADD106R,0.008000X0.008000*%
%ADD107C,0.128000*%
%ADD108C,0.120000*%
%ADD109C,0.258000*%
%ADD110C,0.208000*%
%ADD111C,0.058000*%
%ADD135R,0.033200X0.034770*%
%LNtimecard-dc-beta-v1-1*%
%LPD*%
G54D63*
X0147047Y0024508D03*
G54D64*
X0244685Y0011122D03*
G54D83*
X0309646Y001378D03*
X0187599D03*
X0183661D03*
X0215158D03*
X0211221D03*
X0270275D03*
X0301771D03*
X0297834D03*
X0286023D03*
X0266338D03*
X0282086D03*
X025059D03*
X0246654D03*
X0238779D03*
X0234842D03*
X0219094D03*
X0195473D03*
X0199409D03*
X0203346D03*
X0207283D03*
X0258465D03*
X0242717D03*
X0230906D03*
X027815D03*
X0293898D03*
X0274213D03*
X0305709D03*
X0289961D03*
X0262402D03*
X0254527D03*
X0191535D03*
G54D84*
X0179725Y001573D03*
G54D100*
X019661Y040861D03*
X016661D03*
G54D101*
X0430778Y0258465D03*
X0418966D03*
X0407156D03*
X0398888Y0087992D03*
Y0247835D03*
X055873D03*
Y0167913D03*
Y0087992D03*
G54D102*
X0513622Y0426181D03*
G54D103*
X0523622Y0426181D03*
X0533622D03*
X0543622D03*
G54D104*
X025503Y034252D03*
Y0358268D03*
G54D105*
X0299014Y024384D03*
X0357136Y0209705D03*
Y0130965D03*
X0220274Y024384D03*
X0169644Y013097D03*
Y020971D03*
X0220275Y0095846D03*
X0299015D03*
G54D106*
X0361755Y0248616D03*
X0165255Y0091615D03*
X0165155Y0248616D03*
X0361755Y0091615D03*
G54D107*
X0009984Y0258106D03*
Y0238106D03*
X0029984D03*
Y0258106D03*
X0009984Y0100606D03*
Y0080606D03*
X0029984D03*
Y0100606D03*
X0009984Y0153106D03*
Y0133106D03*
X0029984D03*
Y0153106D03*
X0009984Y0205606D03*
Y0185606D03*
X0029984D03*
Y0205606D03*
G54D108*
X0019984Y0248106D03*
Y0090606D03*
Y0143106D03*
Y0195606D03*
G54D109*
X0028543Y0415206D03*
Y0036811D03*
G54D110*
X0244124Y0317303D03*
X0482313Y0419665D03*
Y0317303D03*
X0244124Y0419665D03*
G54D111*
X0370669Y0072933D03*
G54D135*
X0301984Y0032913D03*
Y0036299D03*
X0234984D03*
Y0032913D03*
X0238984D03*
Y0036299D03*
X0246884D03*
Y0032913D03*
X0251184D03*
Y0036299D03*
X0266484Y0032913D03*
Y0036299D03*
X0270484Y0032913D03*
Y0036299D03*
X0281984Y0032913D03*
Y0036299D03*
X0285484D03*
Y0032913D03*
X0297984D03*
Y0036299D03*
M02*